# T6G (Grand Teton) — schematic netlist excerpt (pin names and nets, part order shuffled) for the footprints in the layout excerpt that follows; sources: Cadence DE-HDL packaged netlist, KiCad conversion of 04192023_DAF0TMB3IC0_F0TG_MB_C_brd_V02_OCP.brd

J69  SCONN288_DDR506112002KQ  IO  pkg DDR288S_1-1VXC  page 93
  VIN_BULK0  = P12V_MEM_CPU0
  RFU0  = NC
  VIN_MGMT  = P3V3_AUX
  HSCL  = I3C_SPD_DDRH_CPU0_SCL
  HSDA  = I3C_SPD_DDRH_CPU0_SDA
  VSS0  = GND
  DQ0_A  = M_H_CPU0_SA_DQ<0>
  VSS1  = GND
  DQ1_A  = M_H_CPU0_SA_DQ<1>
  VSS2  = GND
  DQS0_A_T  = M_H_CPU0_SA_DQS_DP<0>
  DQS0_A_C  = M_H_CPU0_SA_DQS_DN<0>
  VSS3  = GND
  DQ4_A  = M_H_CPU0_SA_DQ<4>
  VSS4  = GND
  DQ5_A  = M_H_CPU0_SA_DQ<5>
  VSS5  = GND
  DQ8_A  = M_H_CPU0_SA_DQ<8>
  VSS6  = GND
  DQ9_A  = M_H_CPU0_SA_DQ<9>
  VSS7  = GND
  DQS1_A_T  = M_H_CPU0_SA_DQS_DP<1>
  DQS1_A_C  = M_H_CPU0_SA_DQS_DN<1>
  VSS8  = GND
  DQ12_A  = M_H_CPU0_SA_DQ<12>
  VSS9  = GND
  DQ13_A  = M_H_CPU0_SA_DQ<13>
  VSS10  = GND
  DQ16_A  = M_H_CPU0_SA_DQ<16>
  VSS11  = GND
  DQ17_A  = M_H_CPU0_SA_DQ<17>
  VSS12  = GND
  DQS2_A_T  = M_H_CPU0_SA_DQS_DP<2>
  DQS2_A_C  = M_H_CPU0_SA_DQS_DN<2>
  VSS13  = GND
  DQ20_A  = M_H_CPU0_SA_DQ<20>
  VSS14  = GND
  DQ21_A  = M_H_CPU0_SA_DQ<21>
  VSS15  = GND
  DQ24_A  = M_H_CPU0_SA_DQ<24>
  VSS16  = GND
  DQ25_A  = M_H_CPU0_SA_DQ<25>
  VSS17  = GND
  DQS3_A_T  = M_H_CPU0_SA_DQS_DP<3>
  DQS3_A_C  = M_H_CPU0_SA_DQS_DN<3>
  VSS18  = GND
  DQ28_A  = M_H_CPU0_SA_DQ<28>
  VSS19  = GND
  DQ29_A  = M_H_CPU0_SA_DQ<29>
  VSS20  = GND
  CB0_A  = M_H_CPU0_SA_CB<0>
  VSS21  = GND
  CB1_A  = M_H_CPU0_SA_CB<1>
  VSS22  = GND
  DQS4_A_T  = M_H_CPU0_SA_DQS_DP<4>
  DQS4_A_C  = M_H_CPU0_SA_DQS_DN<4>
  VSS23  = GND
  CB4_A  = M_H_CPU0_SA_CB<4>
  VSS24  = GND
  CB5_A  = M_H_CPU0_SA_CB<5>
  VSS25  = GND
  ALERT_N  = M_H_CPU0_ALERT_N
  VSS26  = GND
  CS0_A_N  = M_H_CPU0_SA_CS_N<0>
  VSS27  = GND
  CA0_A  = M_H_CPU0_SA_CA<0>
  VSS28  = GND
  CA2_A  = M_H_CPU0_SA_CA<2>
  VSS29  = GND
  CA4_A  = M_H_CPU0_SA_CA<4>
  VSS30  = GND
  CA6_A  = M_H_CPU0_SA_CA<6>
  VSS31  = GND
  PAR_A  = M_H_CPU0_SA_PAR
  VSS32  = GND
  CA0_B  = M_H_CPU0_SB_CA<0>
  VSS33  = GND
  CA2_B  = M_H_CPU0_SB_CA<2>
  VSS34  = GND
  CA4_B  = M_H_CPU0_SB_CA<4>
  VSS35  = GND
  CA6_B  = M_H_CPU0_SB_CA<6>
  VSS36  = GND
  CS0_B_N  = M_H_CPU0_SB_CS_N<0>
  VSS37  = GND
  \lbd||rsp_a_n\  = M_H_CPU0_SA_RSP<0>
  \lbs||rsp_b_n\  = M_H_CPU0_SB_RSP<0>
  VSS38  = GND
  CB4_B  = M_H_CPU0_SB_CB<4>
  VSS39  = GND
  CB5_B  = M_H_CPU0_SB_CB<5>
  VSS40  = GND
  \dqs9_b_t||tdqs9_b_t||dbi4_b_n\  = M_H_CPU0_SB_DQS_DP<9>
  \dqs9_b_c||tdqs9_b_c\  = M_H_CPU0_SB_DQS_DN<9>
  VSS41  = GND
  CB0_B  = M_H_CPU0_SB_CB<0>
  VSS42  = GND
  CB1_B  = M_H_CPU0_SB_CB<1>
  VSS43  = GND
  DQ0_B  = M_H_CPU0_SB_DQ<0>
  VSS44  = GND
  DQ1_B  = M_H_CPU0_SB_DQ<1>
  VSS45  = GND
  DQS0_B_T  = M_H_CPU0_SB_DQS_DP<0>
  DQS0_B_C  = M_H_CPU0_SB_DQS_DN<0>
  VSS46  = GND
  DQ4_B  = M_H_CPU0_SB_DQ<4>
  VSS47  = GND
  DQ5_B  = M_H_CPU0_SB_DQ<5>
  VSS48  = GND
  DQ8_B  = M_H_CPU0_SB_DQ<8>
  VSS49  = GND
  DQ9_B  = M_H_CPU0_SB_DQ<9>
  VSS50  = GND
  DQS1_B_T  = M_H_CPU0_SB_DQS_DP<1>
  DQS1_B_C  = M_H_CPU0_SB_DQS_DN<1>
  VSS51  = GND
  DQ12_B  = M_H_CPU0_SB_DQ<12>
  VSS52  = GND
  DQ13_B  = M_H_CPU0_SB_DQ<13>
  VSS53  = GND
  DQ16_B  = M_H_CPU0_SB_DQ<16>
  VSS54  = GND
  DQ17_B  = M_H_CPU0_SB_DQ<17>
  VSS55  = GND
  DQS2_B_T  = M_H_CPU0_SB_DQS_DP<2>
  DQS2_B_C  = M_H_CPU0_SB_DQS_DN<2>
  VSS56  = GND
  DQ20_B  = M_H_CPU0_SB_DQ<20>
  VSS57  = GND
  DQ21_B  = M_H_CPU0_SB_DQ<21>
  VSS58  = GND
  DQ24_B  = M_H_CPU0_SB_DQ<24>
  VSS59  = GND
  DQ25_B  = M_H_CPU0_SB_DQ<25>
  VSS60  = GND
  DQS3_B_T  = M_H_CPU0_SB_DQS_DP<3>
  DQS3_B_C  = M_H_CPU0_SB_DQS_DN<3>
  VSS61  = GND
  DQ28_B  = M_H_CPU0_SB_DQ<28>
  VSS62  = GND
  DQ29_B  = M_H_CPU0_SB_DQ<29>
  VSS63  = GND
  RFU1  = NC
  VIN_BULK1  = P12V_MEM_CPU0
  VIN_BULK2  = P12V_MEM_CPU0
  \pwr_good||fail_n\  = PWRGD_CHH_CPU0_DIMM
  HAS  = PD_CHH_CPU0_DIMM_SAA
  RFU2  = NC
  RFU3  = NC
  VSS64  = GND
  DQ2_A  = M_H_CPU0_SA_DQ<2>
  VSS65  = GND
  DQ3_A  = M_H_CPU0_SA_DQ<3>
  VSS66  = GND
  \dqs5_a_c||tdqs5_a_c||dqs5_a_t||tdqs5_a_t\  = M_H_CPU0_SA_DQS_DN<5>
  \dqs5_a_t||tdqs5_a_t\  = M_H_CPU0_SA_DQS_DP<5>
  VSS67  = GND
  DQ6_A  = M_H_CPU0_SA_DQ<6>
  VSS68  = GND
  DQ7_A  = M_H_CPU0_SA_DQ<7>
  VSS69  = GND
  DQ10_A  = M_H_CPU0_SA_DQ<10>
  VSS70  = GND
  DQ11_A  = M_H_CPU0_SA_DQ<11>
  VSS71  = GND
  \dqs6_a_c||tdqs6_a_c||dqs6_a_t||tdqs6_a_t\  = M_H_CPU0_SA_DQS_DN<6>
  \dqs6_a_t||tdqs6_a_t\  = M_H_CPU0_SA_DQS_DP<6>
  VSS72  = GND
  DQ14_A  = M_H_CPU0_SA_DQ<14>
  VSS73  = GND
  DQ15_A  = M_H_CPU0_SA_DQ<15>
  VSS74  = GND
  DQ18_A  = M_H_CPU0_SA_DQ<18>
  VSS75  = GND
  DQ19_A  = M_H_CPU0_SA_DQ<19>
  VSS76  = GND
  \dqs7_a_c||tdqs7_a_c\  = M_H_CPU0_SA_DQS_DN<7>
  \dqs7_a_t||tdqs7_a_t\  = M_H_CPU0_SA_DQS_DP<7>
  VSS77  = GND
  DQ22_A  = M_H_CPU0_SA_DQ<22>
  VSS78  = GND
  DQ23_A  = M_H_CPU0_SA_DQ<23>
  VSS79  = GND
  DQ26_A  = M_H_CPU0_SA_DQ<26>
  VSS80  = GND
  DQ27_A  = M_H_CPU0_SA_DQ<27>
  VSS81  = GND
  \dqs8_a_c||tdqs8_a_c\  = M_H_CPU0_SA_DQS_DN<8>
  \dqs8_a_t||tdqs8_a_t\  = M_H_CPU0_SA_DQS_DP<8>
  VSS82  = GND
  DQ30_A  = M_H_CPU0_SA_DQ<30>
  VSS83  = GND
  DQ31_A  = M_H_CPU0_SA_DQ<31>
  VSS84  = GND
  CB2_A  = M_H_CPU0_SA_CB<2>
  VSS85  = GND
  CB3_A  = M_H_CPU0_SA_CB<3>
  VSS86  = GND
  \dqs9_a_c||tdqs9_a_c\  = M_H_CPU0_SA_DQS_DN<9>
  \dqs9_a_t||tdqs9_a_t\  = M_H_CPU0_SA_DQS_DP<9>
  VSS87  = GND
  CB6_A  = M_H_CPU0_SA_CB<6>
  VSS88  = GND
  CB7_A  = M_H_CPU0_SA_CB<7>
  VSS89  = GND
  RESET_N  = M_H_CPU0_RESET_N
  VSS90  = GND
  CS1_A_N  = M_H_CPU0_SA_CS_N<1>
  VSS91  = GND
  CA1_A  = M_H_CPU0_SA_CA<1>
  VSS92  = GND
  CA3_A  = M_H_CPU0_SA_CA<3>
  VSS93  = GND
  CA5_A  = M_H_CPU0_SA_CA<5>
  VSS94  = GND
  CK_T  = M_H_CPU0_CLK_DP<0>
  CK_C  = M_H_CPU0_CLK_DN<0>
  VSS95  = GND
  RFU4  = NC
  CA1_B  = M_H_CPU0_SB_CA<1>
  VSS96  = GND
  CA3_B  = M_H_CPU0_SB_CA<3>
  VSS97  = GND
  CA5_B  = M_H_CPU0_SB_CA<5>
  VSS98  = GND
  PAR_B  = M_H_CPU0_SB_PAR
  VSS99  = GND
  CS1_B_N  = M_H_CPU0_SB_CS_N<1>
  VSS100  = GND
  RFU5  = NC
  RFU6  = NC
  VSS101  = GND
  CB6_B  = M_H_CPU0_SB_CB<6>
  VSS102  = GND
  CB7_B  = M_H_CPU0_SB_CB<7>
  VSS103  = GND
  DQS4_B_C  = M_H_CPU0_SB_DQS_DN<4>
  DQS4_B_T  = M_H_CPU0_SB_DQS_DP<4>
  VSS104  = GND
  CB2_B  = M_H_CPU0_SB_CB<2>
  VSS105  = GND
  CB3_B  = M_H_CPU0_SB_CB<3>
  VSS106  = GND
  DQ2_B  = M_H_CPU0_SB_DQ<2>
  VSS107  = GND
  DQ3_B  = M_H_CPU0_SB_DQ<3>
  VSS108  = GND
  \dqs5_b_c||tdqs5_b_c\  = M_H_CPU0_SB_DQS_DN<5>
  \dqs5_b_t||tdqs5_b_t\  = M_H_CPU0_SB_DQS_DP<5>
  VSS109  = GND
  DQ6_B  = M_H_CPU0_SB_DQ<6>
  VSS110  = GND
  DQ7_B  = M_H_CPU0_SB_DQ<7>
  VSS111  = GND
  DQ10_B  = M_H_CPU0_SB_DQ<10>
  VSS112  = GND
  DQ11_B  = M_H_CPU0_SB_DQ<11>
  VSS113  = GND
  \dqs6_b_c||tdqs6_b_c\  = M_H_CPU0_SB_DQS_DN<6>
  \dqs6_b_t||tdqs6_b_t\  = M_H_CPU0_SB_DQS_DP<6>
  VSS114  = GND
  DQ14_B  = M_H_CPU0_SB_DQ<14>
  VSS115  = GND
  DQ15_B  = M_H_CPU0_SB_DQ<15>
  VSS116  = GND
  DQ18_B  = M_H_CPU0_SB_DQ<18>
  VSS117  = GND
  DQ19_B  = M_H_CPU0_SB_DQ<19>
  VSS118  = GND
  \dqs7_b_c||tdqs7_b_c\  = M_H_CPU0_SB_DQS_DN<7>
  \dqs7_b_t||tdqs7_b_t\  = M_H_CPU0_SB_DQS_DP<7>
  VSS119  = GND
  DQ22_B  = M_H_CPU0_SB_DQ<22>
  VSS120  = GND
  DQ23_B  = M_H_CPU0_SB_DQ<23>
  VSS121  = GND
  DQ26_B  = M_H_CPU0_SB_DQ<26>
  VSS122  = GND
  DQ27_B  = M_H_CPU0_SB_DQ<27>
  VSS123  = GND
  \dqs8_b_c||tdqs8_b_c\  = M_H_CPU0_SB_DQS_DN<8>
  \dqs8_b_t||tdqs8_b_t\  = M_H_CPU0_SB_DQS_DP<8>
  VSS124  = GND
  DQ30_B  = M_H_CPU0_SB_DQ<30>
  VSS125  = GND
  DQ31_B  = M_H_CPU0_SB_DQ<31>
  VSS126  = GND
  G1  = GND
  G2  = GND
  G3  = GND

(kicad_pcb
	(version 20260206)
	(generator "pcbnew")
	(generator_version "10.0")
	(general
		(thickness 1.6)
		(legacy_teardrops no)
	)
	(paper "A4")
	(title_block
		(title "04192023_DAF0TMB3IC0_F0TG_MB_C_brd_V02_OCP.brd")
		(comment 1 "Grand Teton / footprint 2335 of 8354 (J69), pads 277-291 of 291")
	)
	(layers
		(0 "F.Cu" signal "TOP")
		(4 "In1.Cu" signal "GND")
		(6 "In2.Cu" signal "IN1")
		(8 "In3.Cu" signal "GND1")
		(10 "In4.Cu" signal "IN2")
		(12 "In5.Cu" signal "GND2")
		(14 "In6.Cu" signal "IN3")
		(16 "In7.Cu" signal "GND3")
		(18 "In8.Cu" signal "VCC")
		(20 "In9.Cu" signal "VCC1")
		(22 "In10.Cu" signal "GND4")
		(24 "In11.Cu" signal "IN4")
		(26 "In12.Cu" signal "GND5")
		(28 "In13.Cu" signal "IN5")
		(30 "In14.Cu" signal "GND6")
		(32 "In15.Cu" signal "IN6")
		(34 "In16.Cu" signal "GND7")
		(2 "B.Cu" signal "BOTTOM")
		(9 "F.Adhes" user "F.Adhesive")
		(11 "B.Adhes" user "B.Adhesive")
		(13 "F.Paste" user "Package Geometry/Pastemask Top")
		(15 "B.Paste" user "Package Geometry/Pastemask Bottom")
		(5 "F.SilkS" user "Ref Des/Silkscreen Top")
		(7 "B.SilkS" user "Ref Des/Silkscreen Bottom")
		(1 "F.Mask" user "Board Geometry/Soldermask Top")
		(3 "B.Mask" user "Board Geometry/Soldermask Bottom")
		(17 "Dwgs.User" user "User.Drawings")
		(19 "Cmts.User" user "User.Comments")
		(21 "Eco1.User" user "User.Eco1")
		(23 "Eco2.User" user "User.Eco2")
		(25 "Edge.Cuts" user "Board Geometry/Outline")
		(27 "Margin" user)
		(31 "F.CrtYd" user "Package Geometry/Place Bound Top")
		(29 "B.CrtYd" user "Package Geometry/Place Bound Bottom")
		(35 "F.Fab" user "Ref Des/Assembly Top")
		(33 "B.Fab" user "Ref Des/Assembly Bottom")
	)
	(footprint ""
		(layer "F.Cu")
		(at 421.962072 -255.560068 180)
		(property "Reference" "J69"
			(at 3.448304 81.947512 0)
			(unlocked yes)
			(layer "F.SilkS")
			(effects
				(font
					(size 0.7874 0.5842)
					(thickness 0.1524)
				)
			)
		)
		(property "Value" ""
			(at 0 0 180)
			(layer "F.Fab")
			(effects
				(font
					(size 1.27 1.27)
				)
			)
		)
		(duplicate_pad_numbers_are_jumpers no)
		(pad "277" smd rect
			(at 2.050034 53.975 90)
			(size 0.519938 1.4986)
			(layers "F.Cu" "F.Mask" "F.Paste")
			(net "GND")
		)
		(pad "278" smd rect
			(at 2.050034 54.824884 90)
			(size 0.519938 1.4986)
			(layers "F.Cu" "F.Mask" "F.Paste")
			(net "M_H_CPU0_SB_DQ<26>")
		)
		(pad "279" smd rect
			(at 2.050034 55.675022 90)
			(size 0.519938 1.4986)
			(layers "F.Cu" "F.Mask" "F.Paste")
			(net "GND")
		)
		(pad "280" smd rect
			(at 2.050034 56.524906 90)
			(size 0.519938 1.4986)
			(layers "F.Cu" "F.Mask" "F.Paste")
			(net "M_H_CPU0_SB_DQ<27>")
		)
		(pad "281" smd rect
			(at 2.050034 57.375044 90)
			(size 0.519938 1.4986)
			(layers "F.Cu" "F.Mask" "F.Paste")
			(net "GND")
		)
		(pad "282" smd rect
			(at 2.050034 58.224928 90)
			(size 0.519938 1.4986)
			(layers "F.Cu" "F.Mask" "F.Paste")
			(net "M_H_CPU0_SB_DQS_DN<8>")
		)
		(pad "283" smd rect
			(at 2.050034 59.075066 90)
			(size 0.519938 1.4986)
			(layers "F.Cu" "F.Mask" "F.Paste")
			(net "M_H_CPU0_SB_DQS_DP<8>")
		)
		(pad "284" smd rect
			(at 2.050034 59.92495 90)
			(size 0.519938 1.4986)
			(layers "F.Cu" "F.Mask" "F.Paste")
			(net "GND")
		)
		(pad "285" smd rect
			(at 2.050034 60.775088 90)
			(size 0.519938 1.4986)
			(layers "F.Cu" "F.Mask" "F.Paste")
			(net "M_H_CPU0_SB_DQ<30>")
		)
		(pad "286" smd rect
			(at 2.050034 61.624972 90)
			(size 0.519938 1.4986)
			(layers "F.Cu" "F.Mask" "F.Paste")
			(net "GND")
		)
		(pad "287" smd rect
			(at 2.050034 62.47511 90)
			(size 0.519938 1.4986)
			(layers "F.Cu" "F.Mask" "F.Paste")
			(net "M_H_CPU0_SB_DQ<31>")
		)
		(pad "288" smd rect
			(at 2.050034 63.324994 90)
			(size 0.519938 1.4986)
			(layers "F.Cu" "F.Mask" "F.Paste")
			(net "GND")
		)
		(pad "G1" thru_hole oval
			(at 0 -68.97497 90)
			(size 1.7272 3.4798)
			(drill oval 1.2192 2.4638)
			(layers "*.Cu" "*.Mask")
			(remove_unused_layers no)
			(net "GND")
			(clearance 0.127)
			(thermal_gap 0.127)
		)
		(pad "G2" thru_hole oval
			(at 0 3.875024 90)
			(size 1.7272 3.4798)
			(drill oval 1.2192 2.4638)
			(layers "*.Cu" "*.Mask")
			(remove_unused_layers no)
			(net "GND")
			(clearance 0.127)
			(thermal_gap 0.127)
		)
		(pad "G3" thru_hole oval
			(at 0 68.97497 90)
			(size 1.7272 3.4798)
			(drill oval 1.2192 2.4638)
			(layers "*.Cu" "*.Mask")
			(remove_unused_layers no)
			(net "GND")
			(clearance 0.127)
			(thermal_gap 0.127)
		)
	)
)
